(kicad_pcb
	(version 20260206)
	(generator "pcbnew")
	(generator_version "10.0")
	(general
		(thickness 1.6)
		(legacy_teardrops no)
	)
	(paper "A4")
	(title_block
		(title "04192023_DAF0TMB3IC0_F0TG_MB_C_brd_V02_OCP.brd")
		(comment 1 "Grand Teton / footprints 5341-5348 of 8354")
	)
	(layers
		(0 "F.Cu" signal "TOP")
		(4 "In1.Cu" signal "GND")
		(6 "In2.Cu" signal "IN1")
		(8 "In3.Cu" signal "GND1")
		(10 "In4.Cu" signal "IN2")
		(12 "In5.Cu" signal "GND2")
		(14 "In6.Cu" signal "IN3")
		(16 "In7.Cu" signal "GND3")
		(18 "In8.Cu" signal "VCC")
		(20 "In9.Cu" signal "VCC1")
		(22 "In10.Cu" signal "GND4")
		(24 "In11.Cu" signal "IN4")
		(26 "In12.Cu" signal "GND5")
		(28 "In13.Cu" signal "IN5")
		(30 "In14.Cu" signal "GND6")
		(32 "In15.Cu" signal "IN6")
		(34 "In16.Cu" signal "GND7")
		(2 "B.Cu" signal "BOTTOM")
		(9 "F.Adhes" user "F.Adhesive")
		(11 "B.Adhes" user "B.Adhesive")
		(13 "F.Paste" user "Package Geometry/Pastemask Top")
		(15 "B.Paste" user "Package Geometry/Pastemask Bottom")
		(5 "F.SilkS" user "Ref Des/Silkscreen Top")
		(7 "B.SilkS" user "Ref Des/Silkscreen Bottom")
		(1 "F.Mask" user "Board Geometry/Soldermask Top")
		(3 "B.Mask" user "Board Geometry/Soldermask Bottom")
		(17 "Dwgs.User" user "User.Drawings")
		(19 "Cmts.User" user "User.Comments")
		(21 "Eco1.User" user "User.Eco1")
		(23 "Eco2.User" user "User.Eco2")
		(25 "Edge.Cuts" user "Board Geometry/Outline")
		(27 "Margin" user)
		(31 "F.CrtYd" user "Package Geometry/Place Bound Top")
		(29 "B.CrtYd" user "Package Geometry/Place Bound Bottom")
		(35 "F.Fab" user "Ref Des/Assembly Top")
		(33 "B.Fab" user "Ref Des/Assembly Bottom")
	)
	(footprint ""
		(layer "B.Cu")
		(at 322.583556 -395.148562 90)
		(property "Reference" "C577"
			(at 0 0 90)
			(layer "B.SilkS")
			(hide yes)
			(effects
				(font
					(size 1.27 1.27)
				)
				(justify mirror)
			)
		)
		(property "Value" ""
			(at 0 0 90)
			(layer "B.Fab")
			(effects
				(font
					(size 1.27 1.27)
				)
				(justify mirror)
			)
		)
		(duplicate_pad_numbers_are_jumpers no)
		(fp_line
			(start 0.299974 -0.150114)
			(end -0.299974 -0.150114)
			(stroke
				(width 0.1)
				(type default)
			)
			(layer "B.Fab")
		)
		(fp_line
			(start -0.299974 -0.150114)
			(end -0.299974 0.150114)
			(stroke
				(width 0.1)
				(type default)
			)
			(layer "B.Fab")
		)
		(fp_line
			(start 0.299974 0.150114)
			(end 0.299974 -0.150114)
			(stroke
				(width 0.1)
				(type default)
			)
			(layer "B.Fab")
		)
		(fp_line
			(start -0.299974 0.150114)
			(end 0.299974 0.150114)
			(stroke
				(width 0.1)
				(type default)
			)
			(layer "B.Fab")
		)
		(pad "1" smd rect
			(at 0.2667 0 270)
			(size 0.3048 0.381)
			(layers "B.Cu" "B.Mask" "B.Paste")
			(net "P0V9_CPU0_RT0_2A")
		)
		(pad "2" smd rect
			(at -0.2667 0 270)
			(size 0.3048 0.381)
			(layers "B.Cu" "B.Mask" "B.Paste")
			(net "GND")
		)
	)
	(footprint ""
		(layer "B.Cu")
		(at 119.674386 -267.49883)
		(property "Reference" "C2368"
			(at 0 0 0)
			(layer "B.SilkS")
			(hide yes)
			(effects
				(font
					(size 1.27 1.27)
				)
				(justify mirror)
			)
		)
		(property "Value" ""
			(at 0 0 0)
			(layer "B.Fab")
			(effects
				(font
					(size 1.27 1.27)
				)
				(justify mirror)
			)
		)
		(duplicate_pad_numbers_are_jumpers no)
		(fp_line
			(start -0.7874 -0.4064)
			(end -0.7874 0.4064)
			(stroke
				(width 0.1524)
				(type default)
			)
			(layer "B.SilkS")
		)
		(fp_line
			(start -0.7874 0.4064)
			(end 0.7874 0.4064)
			(stroke
				(width 0.1524)
				(type default)
			)
			(layer "B.SilkS")
		)
		(fp_line
			(start 0.7874 -0.4064)
			(end -0.7874 -0.4064)
			(stroke
				(width 0.1524)
				(type default)
			)
			(layer "B.SilkS")
		)
		(fp_line
			(start 0.7874 0.4064)
			(end 0.7874 -0.4064)
			(stroke
				(width 0.1524)
				(type default)
			)
			(layer "B.SilkS")
		)
		(fp_line
			(start -0.67945 -0.3048)
			(end -0.67945 0.3048)
			(stroke
				(width 0.1)
				(type default)
			)
			(layer "B.Fab")
		)
		(fp_line
			(start -0.67945 0.3048)
			(end -0.120396 0.3048)
			(stroke
				(width 0.1)
				(type default)
			)
			(layer "B.Fab")
		)
		(fp_line
			(start -0.12065 -0.3048)
			(end -0.67945 -0.3048)
			(stroke
				(width 0.1)
				(type default)
			)
			(layer "B.Fab")
		)
		(fp_line
			(start -0.12065 -0.2794)
			(end -0.12065 -0.3048)
			(stroke
				(width 0.1)
				(type default)
			)
			(layer "B.Fab")
		)
		(fp_line
			(start -0.120396 0.2794)
			(end 0.12065 0.2794)
			(stroke
				(width 0.1)
				(type default)
			)
			(layer "B.Fab")
		)
		(fp_line
			(start -0.120396 0.3048)
			(end -0.120396 0.2794)
			(stroke
				(width 0.1)
				(type default)
			)
			(layer "B.Fab")
		)
		(fp_line
			(start 0.12065 -0.305054)
			(end 0.12065 -0.2794)
			(stroke
				(width 0.1)
				(type default)
			)
			(layer "B.Fab")
		)
		(fp_line
			(start 0.12065 -0.2794)
			(end -0.12065 -0.2794)
			(stroke
				(width 0.1)
				(type default)
			)
			(layer "B.Fab")
		)
		(fp_line
			(start 0.12065 0.2794)
			(end 0.12065 0.3048)
			(stroke
				(width 0.1)
				(type default)
			)
			(layer "B.Fab")
		)
		(fp_line
			(start 0.12065 0.3048)
			(end 0.67945 0.3048)
			(stroke
				(width 0.1)
				(type default)
			)
			(layer "B.Fab")
		)
		(fp_line
			(start 0.67945 -0.305054)
			(end 0.12065 -0.305054)
			(stroke
				(width 0.1)
				(type default)
			)
			(layer "B.Fab")
		)
		(fp_line
			(start 0.67945 0.3048)
			(end 0.67945 -0.305054)
			(stroke
				(width 0.1)
				(type default)
			)
			(layer "B.Fab")
		)
		(pad "1" smd circle
			(at 0.40005 0 180)
			(size 0 0)
			(layers "B.Cu" "B.Mask" "B.Paste")
			(net "PVDDCR_CPU1_P1")
		)
		(pad "2" smd circle
			(at -0.40005 0 180)
			(size 0 0)
			(layers "B.Cu" "B.Mask" "B.Paste")
			(net "GND")
		)
	)
	(footprint ""
		(layer "B.Cu")
		(at 254.635 -332.867 180)
		(property "Reference" "R842"
			(at 0 0 0)
			(layer "B.SilkS")
			(hide yes)
			(effects
				(font
					(size 1.27 1.27)
				)
				(justify mirror)
			)
		)
		(property "Value" ""
			(at 0 0 0)
			(layer "B.Fab")
			(effects
				(font
					(size 1.27 1.27)
				)
				(justify mirror)
			)
		)
		(duplicate_pad_numbers_are_jumpers no)
		(fp_line
			(start 0.32512 0.175006)
			(end 0.32512 -0.175006)
			(stroke
				(width 0.1)
				(type default)
			)
			(layer "B.Fab")
		)
		(fp_line
			(start 0.32512 -0.175006)
			(end -0.32512 -0.175006)
			(stroke
				(width 0.1)
				(type default)
			)
			(layer "B.Fab")
		)
		(fp_line
			(start -0.32512 0.175006)
			(end 0.32512 0.175006)
			(stroke
				(width 0.1)
				(type default)
			)
			(layer "B.Fab")
		)
		(fp_line
			(start -0.32512 -0.175006)
			(end -0.32512 0.175006)
			(stroke
				(width 0.1)
				(type default)
			)
			(layer "B.Fab")
		)
		(pad "1" smd rect
			(at 0.2667 0)
			(size 0.3048 0.381)
			(layers "B.Cu" "B.Mask" "B.Paste")
			(net "P1V8_AUX")
		)
		(pad "2" smd rect
			(at -0.2667 0 180)
			(size 0.3048 0.381)
			(layers "B.Cu" "B.Mask" "B.Paste")
			(net "RT_ROM_SMB_MUX_ADDR2")
		)
	)
	(footprint ""
		(layer "B.Cu")
		(at 236.8169 -248.285 180)
		(property "Reference" "R328"
			(at 0 0 0)
			(layer "B.SilkS")
			(hide yes)
			(effects
				(font
					(size 1.27 1.27)
				)
				(justify mirror)
			)
		)
		(property "Value" ""
			(at 0 0 0)
			(layer "B.Fab")
			(effects
				(font
					(size 1.27 1.27)
				)
				(justify mirror)
			)
		)
		(duplicate_pad_numbers_are_jumpers no)
		(fp_line
			(start 0.7874 0.4064)
			(end 0.7874 -0.4064)
			(stroke
				(width 0.1524)
				(type default)
			)
			(layer "B.SilkS")
		)
		(fp_line
			(start 0.7874 -0.4064)
			(end -0.7874 -0.4064)
			(stroke
				(width 0.1524)
				(type default)
			)
			(layer "B.SilkS")
		)
		(fp_line
			(start -0.7874 0.4064)
			(end 0.7874 0.4064)
			(stroke
				(width 0.1524)
				(type default)
			)
			(layer "B.SilkS")
		)
		(fp_line
			(start -0.7874 -0.4064)
			(end -0.7874 0.4064)
			(stroke
				(width 0.1524)
				(type default)
			)
			(layer "B.SilkS")
		)
		(fp_line
			(start 0.67945 0.3048)
			(end 0.67945 -0.305054)
			(stroke
				(width 0.1)
				(type default)
			)
			(layer "B.Fab")
		)
		(fp_line
			(start 0.67945 -0.305054)
			(end 0.12065 -0.305054)
			(stroke
				(width 0.1)
				(type default)
			)
			(layer "B.Fab")
		)
		(fp_line
			(start 0.12065 0.3048)
			(end 0.67945 0.3048)
			(stroke
				(width 0.1)
				(type default)
			)
			(layer "B.Fab")
		)
		(fp_line
			(start 0.12065 0.2794)
			(end 0.12065 0.3048)
			(stroke
				(width 0.1)
				(type default)
			)
			(layer "B.Fab")
		)
		(fp_line
			(start 0.12065 -0.2794)
			(end -0.12065 -0.2794)
			(stroke
				(width 0.1)
				(type default)
			)
			(layer "B.Fab")
		)
		(fp_line
			(start 0.12065 -0.305054)
			(end 0.12065 -0.2794)
			(stroke
				(width 0.1)
				(type default)
			)
			(layer "B.Fab")
		)
		(fp_line
			(start -0.120396 0.3048)
			(end -0.120396 0.2794)
			(stroke
				(width 0.1)
				(type default)
			)
			(layer "B.Fab")
		)
		(fp_line
			(start -0.120396 0.2794)
			(end 0.12065 0.2794)
			(stroke
				(width 0.1)
				(type default)
			)
			(layer "B.Fab")
		)
		(fp_line
			(start -0.12065 -0.2794)
			(end -0.12065 -0.3048)
			(stroke
				(width 0.1)
				(type default)
			)
			(layer "B.Fab")
		)
		(fp_line
			(start -0.12065 -0.3048)
			(end -0.67945 -0.3048)
			(stroke
				(width 0.1)
				(type default)
			)
			(layer "B.Fab")
		)
		(fp_line
			(start -0.67945 0.3048)
			(end -0.120396 0.3048)
			(stroke
				(width 0.1)
				(type default)
			)
			(layer "B.Fab")
		)
		(fp_line
			(start -0.67945 -0.3048)
			(end -0.67945 0.3048)
			(stroke
				(width 0.1)
				(type default)
			)
			(layer "B.Fab")
		)
		(pad "1" smd rect
			(at 0.40005 0 180)
			(size 0.4572 0.508)
			(layers "B.Cu" "B.Mask" "B.Paste")
			(net "SMB_APML_CPU0_MUX2_SDA")
		)
		(pad "2" smd rect
			(at -0.40005 0 180)
			(size 0.4572 0.508)
			(layers "B.Cu" "B.Mask" "B.Paste")
			(net "SMB_APML_CPU0_SDA")
		)
	)
	(footprint ""
		(layer "B.Cu")
		(at 239.903 -335.026)
		(property "Reference" "R1390"
			(at 0 0 0)
			(layer "B.SilkS")
			(hide yes)
			(effects
				(font
					(size 1.27 1.27)
				)
				(justify mirror)
			)
		)
		(property "Value" ""
			(at 0 0 0)
			(layer "B.Fab")
			(effects
				(font
					(size 1.27 1.27)
				)
				(justify mirror)
			)
		)
		(duplicate_pad_numbers_are_jumpers no)
		(fp_line
			(start -0.32512 -0.175006)
			(end -0.32512 0.175006)
			(stroke
				(width 0.1)
				(type default)
			)
			(layer "B.Fab")
		)
		(fp_line
			(start -0.32512 0.175006)
			(end 0.32512 0.175006)
			(stroke
				(width 0.1)
				(type default)
			)
			(layer "B.Fab")
		)
		(fp_line
			(start 0.32512 -0.175006)
			(end -0.32512 -0.175006)
			(stroke
				(width 0.1)
				(type default)
			)
			(layer "B.Fab")
		)
		(fp_line
			(start 0.32512 0.175006)
			(end 0.32512 -0.175006)
			(stroke
				(width 0.1)
				(type default)
			)
			(layer "B.Fab")
		)
		(pad "1" smd rect
			(at 0.2667 0 180)
			(size 0.3048 0.381)
			(layers "B.Cu" "B.Mask" "B.Paste")
			(net "P1V8_CPU1_RT_1D")
		)
		(pad "2" smd rect
			(at -0.2667 0)
			(size 0.3048 0.381)
			(layers "B.Cu" "B.Mask" "B.Paste")
			(net "SMB_RT_CPU1_P0_ROM_MUX_2D_R_SCL")
		)
	)
	(footprint ""
		(layer "B.Cu")
		(at 291.52469 -193.99631)
		(property "Reference" "C96"
			(at 0 0 0)
			(layer "B.SilkS")
			(hide yes)
			(effects
				(font
					(size 1.27 1.27)
				)
				(justify mirror)
			)
		)
		(property "Value" ""
			(at 0 0 0)
			(layer "B.Fab")
			(effects
				(font
					(size 1.27 1.27)
				)
				(justify mirror)
			)
		)
		(duplicate_pad_numbers_are_jumpers no)
		(fp_line
			(start -0.7874 -0.4064)
			(end -0.7874 0.4064)
			(stroke
				(width 0.1524)
				(type default)
			)
			(layer "B.SilkS")
		)
		(fp_line
			(start -0.7874 0.4064)
			(end 0.7874 0.4064)
			(stroke
				(width 0.1524)
				(type default)
			)
			(layer "B.SilkS")
		)
		(fp_line
			(start 0.7874 -0.4064)
			(end -0.7874 -0.4064)
			(stroke
				(width 0.1524)
				(type default)
			)
			(layer "B.SilkS")
		)
		(fp_line
			(start 0.7874 0.4064)
			(end 0.7874 -0.4064)
			(stroke
				(width 0.1524)
				(type default)
			)
			(layer "B.SilkS")
		)
		(fp_line
			(start -0.67945 -0.3048)
			(end -0.67945 0.3048)
			(stroke
				(width 0.1)
				(type default)
			)
			(layer "B.Fab")
		)
		(fp_line
			(start -0.67945 0.3048)
			(end -0.120396 0.3048)
			(stroke
				(width 0.1)
				(type default)
			)
			(layer "B.Fab")
		)
		(fp_line
			(start -0.12065 -0.3048)
			(end -0.67945 -0.3048)
			(stroke
				(width 0.1)
				(type default)
			)
			(layer "B.Fab")
		)
		(fp_line
			(start -0.12065 -0.2794)
			(end -0.12065 -0.3048)
			(stroke
				(width 0.1)
				(type default)
			)
			(layer "B.Fab")
		)
		(fp_line
			(start -0.120396 0.2794)
			(end 0.12065 0.2794)
			(stroke
				(width 0.1)
				(type default)
			)
			(layer "B.Fab")
		)
		(fp_line
			(start -0.120396 0.3048)
			(end -0.120396 0.2794)
			(stroke
				(width 0.1)
				(type default)
			)
			(layer "B.Fab")
		)
		(fp_line
			(start 0.12065 -0.305054)
			(end 0.12065 -0.2794)
			(stroke
				(width 0.1)
				(type default)
			)
			(layer "B.Fab")
		)
		(fp_line
			(start 0.12065 -0.2794)
			(end -0.12065 -0.2794)
			(stroke
				(width 0.1)
				(type default)
			)
			(layer "B.Fab")
		)
		(fp_line
			(start 0.12065 0.2794)
			(end 0.12065 0.3048)
			(stroke
				(width 0.1)
				(type default)
			)
			(layer "B.Fab")
		)
		(fp_line
			(start 0.12065 0.3048)
			(end 0.67945 0.3048)
			(stroke
				(width 0.1)
				(type default)
			)
			(layer "B.Fab")
		)
		(fp_line
			(start 0.67945 -0.305054)
			(end 0.12065 -0.305054)
			(stroke
				(width 0.1)
				(type default)
			)
			(layer "B.Fab")
		)
		(fp_line
			(start 0.67945 0.3048)
			(end 0.67945 -0.305054)
			(stroke
				(width 0.1)
				(type default)
			)
			(layer "B.Fab")
		)
		(pad "1" smd circle
			(at 0.40005 0 180)
			(size 0 0)
			(layers "B.Cu" "B.Mask" "B.Paste")
			(net "P3V3_AUX")
		)
		(pad "2" smd circle
			(at -0.40005 0 180)
			(size 0 0)
			(layers "B.Cu" "B.Mask" "B.Paste")
			(net "GND")
		)
	)
	(footprint ""
		(layer "B.Cu")
		(at 410.21889 -398.942052 90)
		(property "Reference" "C971"
			(at 0 0 90)
			(layer "B.SilkS")
			(hide yes)
			(effects
				(font
					(size 1.27 1.27)
				)
				(justify mirror)
			)
		)
		(property "Value" ""
			(at 0 0 90)
			(layer "B.Fab")
			(effects
				(font
					(size 1.27 1.27)
				)
				(justify mirror)
			)
		)
		(duplicate_pad_numbers_are_jumpers no)
		(fp_line
			(start 0.7874 -0.4064)
			(end -0.7874 -0.4064)
			(stroke
				(width 0.1524)
				(type default)
			)
			(layer "B.SilkS")
		)
		(fp_line
			(start -0.7874 -0.4064)
			(end -0.7874 0.4064)
			(stroke
				(width 0.1524)
				(type default)
			)
			(layer "B.SilkS")
		)
		(fp_line
			(start 0.7874 0.4064)
			(end 0.7874 -0.4064)
			(stroke
				(width 0.1524)
				(type default)
			)
			(layer "B.SilkS")
		)
		(fp_line
			(start -0.7874 0.4064)
			(end 0.7874 0.4064)
			(stroke
				(width 0.1524)
				(type default)
			)
			(layer "B.SilkS")
		)
		(fp_line
			(start 0.67945 -0.305054)
			(end 0.12065 -0.305054)
			(stroke
				(width 0.1)
				(type default)
			)
			(layer "B.Fab")
		)
		(fp_line
			(start 0.12065 -0.305054)
			(end 0.12065 -0.2794)
			(stroke
				(width 0.1)
				(type default)
			)
			(layer "B.Fab")
		)
		(fp_line
			(start -0.12065 -0.3048)
			(end -0.67945 -0.3048)
			(stroke
				(width 0.1)
				(type default)
			)
			(layer "B.Fab")
		)
		(fp_line
			(start -0.67945 -0.3048)
			(end -0.67945 0.3048)
			(stroke
				(width 0.1)
				(type default)
			)
			(layer "B.Fab")
		)
		(fp_line
			(start 0.12065 -0.2794)
			(end -0.12065 -0.2794)
			(stroke
				(width 0.1)
				(type default)
			)
			(layer "B.Fab")
		)
		(fp_line
			(start -0.12065 -0.2794)
			(end -0.12065 -0.3048)
			(stroke
				(width 0.1)
				(type default)
			)
			(layer "B.Fab")
		)
		(fp_line
			(start 0.12065 0.2794)
			(end 0.12065 0.3048)
			(stroke
				(width 0.1)
				(type default)
			)
			(layer "B.Fab")
		)
		(fp_line
			(start -0.120396 0.2794)
			(end 0.12065 0.2794)
			(stroke
				(width 0.1)
				(type default)
			)
			(layer "B.Fab")
		)
		(fp_line
			(start 0.67945 0.3048)
			(end 0.67945 -0.305054)
			(stroke
				(width 0.1)
				(type default)
			)
			(layer "B.Fab")
		)
		(fp_line
			(start 0.12065 0.3048)
			(end 0.67945 0.3048)
			(stroke
				(width 0.1)
				(type default)
			)
			(layer "B.Fab")
		)
		(fp_line
			(start -0.120396 0.3048)
			(end -0.120396 0.2794)
			(stroke
				(width 0.1)
				(type default)
			)
			(layer "B.Fab")
		)
		(fp_line
			(start -0.67945 0.3048)
			(end -0.120396 0.3048)
			(stroke
				(width 0.1)
				(type default)
			)
			(layer "B.Fab")
		)
		(pad "1" smd circle
			(at 0.40005 0 270)
			(size 0 0)
			(layers "B.Cu" "B.Mask" "B.Paste")
			(net "P0V9_CPU0_RT_2D")
		)
		(pad "2" smd circle
			(at -0.40005 0 270)
			(size 0 0)
			(layers "B.Cu" "B.Mask" "B.Paste")
			(net "GND")
		)
	)
	(footprint ""
		(layer "B.Cu")
		(at 358.779826 -392.957558)
		(property "Reference" "L13"
			(at 0 0 0)
			(layer "B.SilkS")
			(hide yes)
			(effects
				(font
					(size 1.27 1.27)
				)
				(justify mirror)
			)
		)
		(property "Value" ""
			(at 0 0 0)
			(layer "B.Fab")
			(effects
				(font
					(size 1.27 1.27)
				)
				(justify mirror)
			)
		)
		(duplicate_pad_numbers_are_jumpers no)
		(fp_line
			(start -1.63576 -0.8128)
			(end -1.63576 0.8128)
			(stroke
				(width 0.1524)
				(type default)
			)
			(layer "B.SilkS")
		)
		(fp_line
			(start -1.63576 0.8128)
			(end 1.63576 0.8128)
			(stroke
				(width 0.1524)
				(type default)
			)
			(layer "B.SilkS")
		)
		(fp_line
			(start 1.63576 -0.8128)
			(end -1.63576 -0.8128)
			(stroke
				(width 0.1524)
				(type default)
			)
			(layer "B.SilkS")
		)
		(fp_line
			(start 1.63576 -0.8128)
			(end 1.63576 0.8128)
			(stroke
				(width 0.1524)
				(type default)
			)
			(layer "B.SilkS")
		)
		(fp_line
			(start -1.560576 -0.738632)
			(end 1.56083 -0.738632)
			(stroke
				(width 0.1)
				(type default)
			)
			(layer "B.Fab")
		)
		(fp_line
			(start -1.560576 0.7366)
			(end -1.560576 -0.738632)
			(stroke
				(width 0.1)
				(type default)
			)
			(layer "B.Fab")
		)
		(fp_line
			(start -1.524 0.7366)
			(end -1.560576 0.7366)
			(stroke
				(width 0.1)
				(type default)
			)
			(layer "B.Fab")
		)
		(fp_line
			(start 1.524 0.7366)
			(end -1.524 0.7366)
			(stroke
				(width 0.1)
				(type default)
			)
			(layer "B.Fab")
		)
		(fp_line
			(start 1.56083 -0.738632)
			(end 1.56083 0.7366)
			(stroke
				(width 0.1)
				(type default)
			)
			(layer "B.Fab")
		)
		(fp_line
			(start 1.56083 0.7366)
			(end 1.524 0.7366)
			(stroke
				(width 0.1)
				(type default)
			)
			(layer "B.Fab")
		)
		(pad "1" smd rect
			(at 0.94996 0)
			(size 1.1176 1.3716)
			(layers "B.Cu" "B.Mask" "B.Paste")
			(net "P1V8_CPU0_RT_1D")
		)
		(pad "2" smd rect
			(at -0.94996 0)
			(size 1.1176 1.3716)
			(layers "B.Cu" "B.Mask" "B.Paste")
			(net "P1V8_CPU0_RT1_1A")
		)
	)
)
